# BASEBOARD_FAB2 (Tioga Pass) — schematic netlist excerpt (pin names and nets, part order shuffled) for the footprints in the layout excerpt that follows; sources: Cadence DE-HDL packaged netlist, KiCad conversion of Wiwynn_Tioga_Pass_MB.brd

C9R13  CAP_A  0.1UF 16V 10% X7R  pkg 0402V  page 167 : A = P3V3_STBY ; B = GND
R25W174  RES  10.0K 1% CHIP  pkg 0402  page 254 : A = P3V3_STBY ; B = BMC_JTAG_SEL_N
R2U17  RES  0.0 5% CHIP  pkg 0402  page 107 : A = P3E_CPU0_PE1_SS_RXN<1> ; B = P3E_CPU0_PE1_SS_R_RXN<1>

(kicad_pcb
	(version 20260206)
	(generator "pcbnew")
	(generator_version "10.0")
	(general
		(thickness 1.6)
		(legacy_teardrops no)
	)
	(paper "A4")
	(title_block
		(title "Wiwynn_Tioga_Pass_MB.brd")
		(comment 1 "Tioga Pass / footprints 2902-2904 of 4770")
	)
	(layers
		(0 "F.Cu" signal "TOP")
		(4 "In1.Cu" signal "L2GND")
		(6 "In2.Cu" signal "L3")
		(8 "In3.Cu" signal "L4GND")
		(10 "In4.Cu" signal "L5")
		(12 "In5.Cu" signal "L6GND")
		(14 "In6.Cu" signal "L7VCC")
		(16 "In7.Cu" signal "L8VCC")
		(18 "In8.Cu" signal "L9GND")
		(20 "In9.Cu" signal "L10")
		(22 "In10.Cu" signal "L11GND")
		(24 "In11.Cu" signal "L12")
		(26 "In12.Cu" signal "L13GND")
		(2 "B.Cu" signal "BOTTOM")
		(9 "F.Adhes" user "F.Adhesive")
		(11 "B.Adhes" user "B.Adhesive")
		(13 "F.Paste" user "Package Geometry/Pastemask Top")
		(15 "B.Paste" user "Package Geometry/Pastemask Bottom")
		(5 "F.SilkS" user "Ref Des/Silkscreen Top")
		(7 "B.SilkS" user "Ref Des/Silkscreen Bottom")
		(1 "F.Mask" user "Board Geometry/Soldermask Top")
		(3 "B.Mask" user "Board Geometry/Soldermask Bottom")
		(17 "Dwgs.User" user "User.Drawings")
		(19 "Cmts.User" user "User.Comments")
		(21 "Eco1.User" user "User.Eco1")
		(23 "Eco2.User" user "User.Eco2")
		(25 "Edge.Cuts" user "Board Geometry/Outline")
		(27 "Margin" user)
		(31 "F.CrtYd" user "Package Geometry/Place Bound Top")
		(29 "B.CrtYd" user "Package Geometry/Place Bound Bottom")
		(35 "F.Fab" user "Ref Des/Assembly Top")
		(33 "B.Fab" user "Ref Des/Assembly Bottom")
	)
	(footprint ""
		(layer "B.Cu")
		(at 337.537806 -60.368434)
		(property "Reference" "R2U17"
			(at 0 0 0)
			(layer "B.SilkS")
			(hide yes)
			(effects
				(font
					(size 1.27 1.27)
				)
				(justify mirror)
			)
		)
		(property "Value" ""
			(at 0 0 0)
			(layer "B.Fab")
			(effects
				(font
					(size 1.27 1.27)
				)
				(justify mirror)
			)
		)
		(duplicate_pad_numbers_are_jumpers no)
		(fp_poly
			(pts
				(xy 0.2794 -0.1016) (xy -0.2794 -0.1016) (xy -0.2794 0.9906) (xy 0.2794 0.9906)
			)
			(stroke
				(width 0)
				(type default)
			)
			(fill no)
			(layer "B.CrtYd")
		)
		(fp_line
			(start -0.2794 -0.1016)
			(end 0.2794 -0.1016)
			(stroke
				(width 0.1)
				(type default)
			)
			(layer "B.Fab")
		)
		(fp_line
			(start -0.2794 0.9906)
			(end -0.2794 -0.1016)
			(stroke
				(width 0.1)
				(type default)
			)
			(layer "B.Fab")
		)
		(fp_line
			(start 0.2794 -0.1016)
			(end 0.2794 0.9906)
			(stroke
				(width 0.1)
				(type default)
			)
			(layer "B.Fab")
		)
		(fp_line
			(start 0.2794 0.9906)
			(end -0.2794 0.9906)
			(stroke
				(width 0.1)
				(type default)
			)
			(layer "B.Fab")
		)
		(pad "1" smd rect
			(at 0 0 180)
			(size 0.508 0.508)
			(layers "B.Cu" "B.Mask" "B.Paste")
			(net "P3E_CPU0_PE1_SS_RXN<1>")
		)
		(pad "2" smd rect
			(at 0 0.889 180)
			(size 0.508 0.508)
			(layers "B.Cu" "B.Mask" "B.Paste")
			(net "P3E_CPU0_PE1_SS_R_RXN<1>")
		)
		(zone
			(layer "B.Cu")
			(hatch none 0.5)
			(connect_pads
				(clearance 0)
			)
			(min_thickness 0.25)
			(keepout
				(tracks allowed)
				(vias not_allowed)
				(pads allowed)
				(copperpour not_allowed)
				(footprints allowed)
			)
			(placement
				(enabled no)
				(sheetname "")
			)
			(fill
				(thermal_gap 0.5)
				(thermal_bridge_width 0.5)
				(island_removal_mode 0)
			)
			(polygon
				(pts
					(xy 337.791806 -60.114434) (xy 337.283806 -60.114434) (xy 337.283806 -59.733434) (xy 337.791806 -59.733434)
				)
			)
		)
		(zone
			(layer "B.Cu")
			(hatch none 0.5)
			(connect_pads
				(clearance 0)
			)
			(min_thickness 0.25)
			(keepout
				(tracks not_allowed)
				(vias allowed)
				(pads allowed)
				(copperpour not_allowed)
				(footprints allowed)
			)
			(placement
				(enabled no)
				(sheetname "")
			)
			(fill
				(thermal_gap 0.5)
				(thermal_bridge_width 0.5)
				(island_removal_mode 0)
			)
			(polygon
				(pts
					(xy 337.791806 -59.733434) (xy 337.283806 -59.733434) (xy 337.283806 -60.114434) (xy 337.791806 -60.114434)
				)
			)
		)
	)
	(footprint ""
		(layer "B.Cu")
		(at 19.05 -45.72)
		(property "Reference" "C9R13"
			(at 0 0 0)
			(layer "B.SilkS")
			(hide yes)
			(effects
				(font
					(size 1.27 1.27)
				)
				(justify mirror)
			)
		)
		(property "Value" ""
			(at 0 0 0)
			(layer "B.Fab")
			(effects
				(font
					(size 1.27 1.27)
				)
				(justify mirror)
			)
		)
		(duplicate_pad_numbers_are_jumpers no)
		(fp_poly
			(pts
				(xy -0.3048 -0.1016) (xy -0.3048 0.9906) (xy 0.3048 0.9906) (xy 0.3048 -0.1016)
			)
			(stroke
				(width 0)
				(type default)
			)
			(fill no)
			(layer "B.CrtYd")
		)
		(fp_line
			(start -0.3048 -0.1016)
			(end 0.3048 -0.1016)
			(stroke
				(width 0.1)
				(type default)
			)
			(layer "B.Fab")
		)
		(fp_line
			(start -0.3048 0.9906)
			(end -0.3048 -0.1016)
			(stroke
				(width 0.1)
				(type default)
			)
			(layer "B.Fab")
		)
		(fp_line
			(start 0.3048 -0.1016)
			(end 0.3048 0.9906)
			(stroke
				(width 0.1)
				(type default)
			)
			(layer "B.Fab")
		)
		(fp_line
			(start 0.3048 0.9906)
			(end -0.3048 0.9906)
			(stroke
				(width 0.1)
				(type default)
			)
			(layer "B.Fab")
		)
		(pad "1" smd rect
			(at 0 0 180)
			(size 0.508 0.508)
			(layers "B.Cu" "B.Mask" "B.Paste")
			(net "P3V3_STBY")
		)
		(pad "2" smd rect
			(at 0 0.889 180)
			(size 0.508 0.508)
			(layers "B.Cu" "B.Mask" "B.Paste")
			(net "GND")
		)
		(zone
			(layer "B.Cu")
			(hatch none 0.5)
			(connect_pads
				(clearance 0)
			)
			(min_thickness 0.25)
			(keepout
				(tracks allowed)
				(vias not_allowed)
				(pads allowed)
				(copperpour not_allowed)
				(footprints allowed)
			)
			(placement
				(enabled no)
				(sheetname "")
			)
			(fill
				(thermal_gap 0.5)
				(thermal_bridge_width 0.5)
				(island_removal_mode 0)
			)
			(polygon
				(pts
					(xy 19.304 -45.466) (xy 18.796 -45.466) (xy 18.796 -45.085) (xy 19.304 -45.085)
				)
			)
		)
		(zone
			(layer "B.Cu")
			(hatch none 0.5)
			(connect_pads
				(clearance 0)
			)
			(min_thickness 0.25)
			(keepout
				(tracks not_allowed)
				(vias allowed)
				(pads allowed)
				(copperpour not_allowed)
				(footprints allowed)
			)
			(placement
				(enabled no)
				(sheetname "")
			)
			(fill
				(thermal_gap 0.5)
				(thermal_bridge_width 0.5)
				(island_removal_mode 0)
			)
			(polygon
				(pts
					(xy 19.304 -45.085) (xy 18.796 -45.085) (xy 18.796 -45.466) (xy 19.304 -45.466)
				)
			)
		)
	)
	(footprint ""
		(layer "B.Cu")
		(at 438.6199 -141.097 180)
		(property "Reference" "R25W174"
			(at 0.8382 -0.67818 180)
			(unlocked yes)
			(layer "B.SilkS")
			(effects
				(font
					(size 0.4064 0.254)
					(thickness 0.1524)
				)
				(justify left mirror)
			)
		)
		(property "Value" ""
			(at 0 0 0)
			(layer "B.Fab")
			(effects
				(font
					(size 1.27 1.27)
				)
				(justify mirror)
			)
		)
		(duplicate_pad_numbers_are_jumpers no)
		(fp_poly
			(pts
				(xy 0.2794 -0.1016) (xy -0.2794 -0.1016) (xy -0.2794 0.9906) (xy 0.2794 0.9906)
			)
			(stroke
				(width 0)
				(type default)
			)
			(fill no)
			(layer "B.CrtYd")
		)
		(fp_line
			(start 0.2794 0.9906)
			(end -0.2794 0.9906)
			(stroke
				(width 0.1)
				(type default)
			)
			(layer "B.Fab")
		)
		(fp_line
			(start 0.2794 -0.1016)
			(end 0.2794 0.9906)
			(stroke
				(width 0.1)
				(type default)
			)
			(layer "B.Fab")
		)
		(fp_line
			(start -0.2794 0.9906)
			(end -0.2794 -0.1016)
			(stroke
				(width 0.1)
				(type default)
			)
			(layer "B.Fab")
		)
		(fp_line
			(start -0.2794 -0.1016)
			(end 0.2794 -0.1016)
			(stroke
				(width 0.1)
				(type default)
			)
			(layer "B.Fab")
		)
		(pad "1" smd rect
			(at 0 0)
			(size 0.508 0.508)
			(layers "B.Cu" "B.Mask" "B.Paste")
			(net "P3V3_STBY")
		)
		(pad "2" smd rect
			(at 0 0.889)
			(size 0.508 0.508)
			(layers "B.Cu" "B.Mask" "B.Paste")
			(net "BMC_JTAG_SEL_N")
		)
		(zone
			(layer "B.Cu")
			(hatch none 0.5)
			(connect_pads
				(clearance 0)
			)
			(min_thickness 0.25)
			(keepout
				(tracks not_allowed)
				(vias allowed)
				(pads allowed)
				(copperpour not_allowed)
				(footprints allowed)
			)
			(placement
				(enabled no)
				(sheetname "")
			)
			(fill
				(thermal_gap 0.5)
				(thermal_bridge_width 0.5)
				(island_removal_mode 0)
			)
			(polygon
				(pts
					(xy 438.3659 -141.732) (xy 438.8739 -141.732) (xy 438.8739 -141.351) (xy 438.3659 -141.351)
				)
			)
		)
		(zone
			(layer "B.Cu")
			(hatch none 0.5)
			(connect_pads
				(clearance 0)
			)
			(min_thickness 0.25)
			(keepout
				(tracks allowed)
				(vias not_allowed)
				(pads allowed)
				(copperpour not_allowed)
				(footprints allowed)
			)
			(placement
				(enabled no)
				(sheetname "")
			)
			(fill
				(thermal_gap 0.5)
				(thermal_bridge_width 0.5)
				(island_removal_mode 0)
			)
			(polygon
				(pts
					(xy 438.3659 -141.351) (xy 438.8739 -141.351) (xy 438.8739 -141.732) (xy 438.3659 -141.732)
				)
			)
		)
	)
)
